#ISCELL
  pure_quanta quanta_title_block_c *
  *
#CELL
  pure_quanta genoa_sp5 *
  page30_i28
#CELL
  pure_quanta genoa_sp5 *
  page30_i29
#ISCELL
  pure_quanta_power vcc_core *
  page30_i40
#ISCELL
  pure_quanta_power universal_power *
  page30_i41
#CELL
  pure_quanta genoa_sp5 *
  page30_i42
#ISCELL
  pure_quanta_power vcc_core *
  page30_i43
#CELL
  pure_quanta genoa_sp5 *
  page30_i45
#ISCELL
  pure_quanta_power vcc_core *
  page30_i46
#ISCELL
  pure_quanta_power vcc_core *
  page30_i47
#CELL
  pure_quanta genoa_sp5 *
  page30_i50
#ISCELL
  pure_quanta_power vcc_core *
  page30_i51
#ISCELL
  pure_quanta_power vcc_core *
  page30_i52
#ISCELL
  pure_quanta_power universal_power *
  page30_i53
#ISCELL
  pure_quanta_power universal_power *
  page30_i55
#ISCELL
  pure_quanta_power vcc_core *
  page30_i56
#ISCELL
  pure_quanta_power vcc_core *
  page30_i57
